(kicad_pcb
	(version 20260206)
	(generator "pcbnew")
	(generator_version "10.0")
	(general
		(thickness 1.6)
		(legacy_teardrops no)
	)
	(paper "A4")
	(title_block
		(title "Wiwynn_Tioga_Pass_MB.brd")
		(comment 1 "Tioga Pass / footprints 3412-3418 of 4770")
	)
	(layers
		(0 "F.Cu" signal "TOP")
		(4 "In1.Cu" signal "L2GND")
		(6 "In2.Cu" signal "L3")
		(8 "In3.Cu" signal "L4GND")
		(10 "In4.Cu" signal "L5")
		(12 "In5.Cu" signal "L6GND")
		(14 "In6.Cu" signal "L7VCC")
		(16 "In7.Cu" signal "L8VCC")
		(18 "In8.Cu" signal "L9GND")
		(20 "In9.Cu" signal "L10")
		(22 "In10.Cu" signal "L11GND")
		(24 "In11.Cu" signal "L12")
		(26 "In12.Cu" signal "L13GND")
		(2 "B.Cu" signal "BOTTOM")
		(9 "F.Adhes" user "F.Adhesive")
		(11 "B.Adhes" user "B.Adhesive")
		(13 "F.Paste" user "Package Geometry/Pastemask Top")
		(15 "B.Paste" user "Package Geometry/Pastemask Bottom")
		(5 "F.SilkS" user "Ref Des/Silkscreen Top")
		(7 "B.SilkS" user "Ref Des/Silkscreen Bottom")
		(1 "F.Mask" user "Board Geometry/Soldermask Top")
		(3 "B.Mask" user "Board Geometry/Soldermask Bottom")
		(17 "Dwgs.User" user "User.Drawings")
		(19 "Cmts.User" user "User.Comments")
		(21 "Eco1.User" user "User.Eco1")
		(23 "Eco2.User" user "User.Eco2")
		(25 "Edge.Cuts" user "Board Geometry/Outline")
		(27 "Margin" user)
		(31 "F.CrtYd" user "Package Geometry/Place Bound Top")
		(29 "B.CrtYd" user "Package Geometry/Place Bound Bottom")
		(35 "F.Fab" user "Ref Des/Assembly Top")
		(33 "B.Fab" user "Ref Des/Assembly Bottom")
	)
	(footprint ""
		(layer "B.Cu")
		(at 462.801208 -136.525254 90)
		(property "Reference" "R1L41"
			(at 0 0 90)
			(layer "B.SilkS")
			(hide yes)
			(effects
				(font
					(size 1.27 1.27)
				)
				(justify mirror)
			)
		)
		(property "Value" ""
			(at 0 0 90)
			(layer "B.Fab")
			(effects
				(font
					(size 1.27 1.27)
				)
				(justify mirror)
			)
		)
		(duplicate_pad_numbers_are_jumpers no)
		(fp_poly
			(pts
				(xy 0.2794 -0.1016) (xy -0.2794 -0.1016) (xy -0.2794 0.9906) (xy 0.2794 0.9906)
			)
			(stroke
				(width 0)
				(type default)
			)
			(fill no)
			(layer "B.CrtYd")
		)
		(fp_line
			(start 0.2794 -0.1016)
			(end 0.2794 0.9906)
			(stroke
				(width 0.1)
				(type default)
			)
			(layer "B.Fab")
		)
		(fp_line
			(start -0.2794 -0.1016)
			(end 0.2794 -0.1016)
			(stroke
				(width 0.1)
				(type default)
			)
			(layer "B.Fab")
		)
		(fp_line
			(start 0.2794 0.9906)
			(end -0.2794 0.9906)
			(stroke
				(width 0.1)
				(type default)
			)
			(layer "B.Fab")
		)
		(fp_line
			(start -0.2794 0.9906)
			(end -0.2794 -0.1016)
			(stroke
				(width 0.1)
				(type default)
			)
			(layer "B.Fab")
		)
		(pad "1" smd rect
			(at 0 0 270)
			(size 0.508 0.508)
			(layers "B.Cu" "B.Mask" "B.Paste")
			(net "P1V05_PCH_STBY")
		)
		(pad "2" smd rect
			(at 0 0.889 270)
			(size 0.508 0.508)
			(layers "B.Cu" "B.Mask" "B.Paste")
			(net "XDP_PREQ_N")
		)
		(zone
			(layer "B.Cu")
			(hatch none 0.5)
			(connect_pads
				(clearance 0)
			)
			(min_thickness 0.25)
			(keepout
				(tracks allowed)
				(vias not_allowed)
				(pads allowed)
				(copperpour not_allowed)
				(footprints allowed)
			)
			(placement
				(enabled no)
				(sheetname "")
			)
			(fill
				(thermal_gap 0.5)
				(thermal_bridge_width 0.5)
				(island_removal_mode 0)
			)
			(polygon
				(pts
					(xy 463.055208 -136.779254) (xy 463.055208 -136.271254) (xy 463.436208 -136.271254) (xy 463.436208 -136.779254)
				)
			)
		)
		(zone
			(layer "B.Cu")
			(hatch none 0.5)
			(connect_pads
				(clearance 0)
			)
			(min_thickness 0.25)
			(keepout
				(tracks not_allowed)
				(vias allowed)
				(pads allowed)
				(copperpour not_allowed)
				(footprints allowed)
			)
			(placement
				(enabled no)
				(sheetname "")
			)
			(fill
				(thermal_gap 0.5)
				(thermal_bridge_width 0.5)
				(island_removal_mode 0)
			)
			(polygon
				(pts
					(xy 463.436208 -136.779254) (xy 463.436208 -136.271254) (xy 463.055208 -136.271254) (xy 463.055208 -136.779254)
				)
			)
		)
	)
	(footprint ""
		(layer "B.Cu")
		(at 447.6242 -12.2174 180)
		(property "Reference" "C2U26"
			(at 0 0 0)
			(layer "B.SilkS")
			(hide yes)
			(effects
				(font
					(size 1.27 1.27)
				)
				(justify mirror)
			)
		)
		(property "Value" ""
			(at 0 0 0)
			(layer "B.Fab")
			(effects
				(font
					(size 1.27 1.27)
				)
				(justify mirror)
			)
		)
		(duplicate_pad_numbers_are_jumpers no)
		(fp_poly
			(pts
				(xy -0.3048 -0.1016) (xy -0.3048 0.9906) (xy 0.3048 0.9906) (xy 0.3048 -0.1016)
			)
			(stroke
				(width 0)
				(type default)
			)
			(fill no)
			(layer "B.CrtYd")
		)
		(fp_line
			(start 0.3048 0.9906)
			(end -0.3048 0.9906)
			(stroke
				(width 0.1)
				(type default)
			)
			(layer "B.Fab")
		)
		(fp_line
			(start 0.3048 -0.1016)
			(end 0.3048 0.9906)
			(stroke
				(width 0.1)
				(type default)
			)
			(layer "B.Fab")
		)
		(fp_line
			(start -0.3048 0.9906)
			(end -0.3048 -0.1016)
			(stroke
				(width 0.1)
				(type default)
			)
			(layer "B.Fab")
		)
		(fp_line
			(start -0.3048 -0.1016)
			(end 0.3048 -0.1016)
			(stroke
				(width 0.1)
				(type default)
			)
			(layer "B.Fab")
		)
		(pad "1" smd rect
			(at 0 0)
			(size 0.508 0.508)
			(layers "B.Cu" "B.Mask" "B.Paste")
			(net "P3V3_RTC_STBY")
		)
		(pad "2" smd rect
			(at 0 0.889)
			(size 0.508 0.508)
			(layers "B.Cu" "B.Mask" "B.Paste")
			(net "GND")
		)
		(zone
			(layer "B.Cu")
			(hatch none 0.5)
			(connect_pads
				(clearance 0)
			)
			(min_thickness 0.25)
			(keepout
				(tracks not_allowed)
				(vias allowed)
				(pads allowed)
				(copperpour not_allowed)
				(footprints allowed)
			)
			(placement
				(enabled no)
				(sheetname "")
			)
			(fill
				(thermal_gap 0.5)
				(thermal_bridge_width 0.5)
				(island_removal_mode 0)
			)
			(polygon
				(pts
					(xy 447.3702 -12.8524) (xy 447.8782 -12.8524) (xy 447.8782 -12.4714) (xy 447.3702 -12.4714)
				)
			)
		)
		(zone
			(layer "B.Cu")
			(hatch none 0.5)
			(connect_pads
				(clearance 0)
			)
			(min_thickness 0.25)
			(keepout
				(tracks allowed)
				(vias not_allowed)
				(pads allowed)
				(copperpour not_allowed)
				(footprints allowed)
			)
			(placement
				(enabled no)
				(sheetname "")
			)
			(fill
				(thermal_gap 0.5)
				(thermal_bridge_width 0.5)
				(island_removal_mode 0)
			)
			(polygon
				(pts
					(xy 447.3702 -12.4714) (xy 447.8782 -12.4714) (xy 447.8782 -12.8524) (xy 447.3702 -12.8524)
				)
			)
		)
	)
	(footprint ""
		(layer "B.Cu")
		(at 481.965 -32.512 180)
		(property "Reference" "R2T47"
			(at 0 0 0)
			(layer "B.SilkS")
			(hide yes)
			(effects
				(font
					(size 1.27 1.27)
				)
				(justify mirror)
			)
		)
		(property "Value" ""
			(at 0 0 0)
			(layer "B.Fab")
			(effects
				(font
					(size 1.27 1.27)
				)
				(justify mirror)
			)
		)
		(duplicate_pad_numbers_are_jumpers no)
		(fp_poly
			(pts
				(xy 0.2794 -0.1016) (xy -0.2794 -0.1016) (xy -0.2794 0.9906) (xy 0.2794 0.9906)
			)
			(stroke
				(width 0)
				(type default)
			)
			(fill no)
			(layer "B.CrtYd")
		)
		(fp_line
			(start 0.2794 0.9906)
			(end -0.2794 0.9906)
			(stroke
				(width 0.1)
				(type default)
			)
			(layer "B.Fab")
		)
		(fp_line
			(start 0.2794 -0.1016)
			(end 0.2794 0.9906)
			(stroke
				(width 0.1)
				(type default)
			)
			(layer "B.Fab")
		)
		(fp_line
			(start -0.2794 0.9906)
			(end -0.2794 -0.1016)
			(stroke
				(width 0.1)
				(type default)
			)
			(layer "B.Fab")
		)
		(fp_line
			(start -0.2794 -0.1016)
			(end 0.2794 -0.1016)
			(stroke
				(width 0.1)
				(type default)
			)
			(layer "B.Fab")
		)
		(pad "1" smd rect
			(at 0 0)
			(size 0.508 0.508)
			(layers "B.Cu" "B.Mask" "B.Paste")
			(net "CLK_25M_CPLD_R")
		)
		(pad "2" smd rect
			(at 0 0.889)
			(size 0.508 0.508)
			(layers "B.Cu" "B.Mask" "B.Paste")
			(net "CLK_25M_CPLD")
		)
		(zone
			(layer "B.Cu")
			(hatch none 0.5)
			(connect_pads
				(clearance 0)
			)
			(min_thickness 0.25)
			(keepout
				(tracks not_allowed)
				(vias allowed)
				(pads allowed)
				(copperpour not_allowed)
				(footprints allowed)
			)
			(placement
				(enabled no)
				(sheetname "")
			)
			(fill
				(thermal_gap 0.5)
				(thermal_bridge_width 0.5)
				(island_removal_mode 0)
			)
			(polygon
				(pts
					(xy 481.711 -33.147) (xy 482.219 -33.147) (xy 482.219 -32.766) (xy 481.711 -32.766)
				)
			)
		)
		(zone
			(layer "B.Cu")
			(hatch none 0.5)
			(connect_pads
				(clearance 0)
			)
			(min_thickness 0.25)
			(keepout
				(tracks allowed)
				(vias not_allowed)
				(pads allowed)
				(copperpour not_allowed)
				(footprints allowed)
			)
			(placement
				(enabled no)
				(sheetname "")
			)
			(fill
				(thermal_gap 0.5)
				(thermal_bridge_width 0.5)
				(island_removal_mode 0)
			)
			(polygon
				(pts
					(xy 481.711 -32.766) (xy 482.219 -32.766) (xy 482.219 -33.147) (xy 481.711 -33.147)
				)
			)
		)
	)
	(footprint ""
		(layer "B.Cu")
		(at 385.34594 -29.555694 90)
		(property "Reference" "C2T11"
			(at 0 0 90)
			(layer "B.SilkS")
			(hide yes)
			(effects
				(font
					(size 1.27 1.27)
				)
				(justify mirror)
			)
		)
		(property "Value" ""
			(at 0 0 90)
			(layer "B.Fab")
			(effects
				(font
					(size 1.27 1.27)
				)
				(justify mirror)
			)
		)
		(duplicate_pad_numbers_are_jumpers no)
		(fp_poly
			(pts
				(xy -0.3048 -0.1016) (xy -0.3048 0.9906) (xy 0.3048 0.9906) (xy 0.3048 -0.1016)
			)
			(stroke
				(width 0)
				(type default)
			)
			(fill no)
			(layer "B.CrtYd")
		)
		(fp_line
			(start 0.3048 -0.1016)
			(end 0.3048 0.9906)
			(stroke
				(width 0.1)
				(type default)
			)
			(layer "B.Fab")
		)
		(fp_line
			(start -0.3048 -0.1016)
			(end 0.3048 -0.1016)
			(stroke
				(width 0.1)
				(type default)
			)
			(layer "B.Fab")
		)
		(fp_line
			(start 0.3048 0.9906)
			(end -0.3048 0.9906)
			(stroke
				(width 0.1)
				(type default)
			)
			(layer "B.Fab")
		)
		(fp_line
			(start -0.3048 0.9906)
			(end -0.3048 -0.1016)
			(stroke
				(width 0.1)
				(type default)
			)
			(layer "B.Fab")
		)
		(pad "1" smd rect
			(at 0 0 270)
			(size 0.508 0.508)
			(layers "B.Cu" "B.Mask" "B.Paste")
			(net "P3E_PCH_M2_TX_C_DN<1>")
		)
		(pad "2" smd rect
			(at 0 0.889 270)
			(size 0.508 0.508)
			(layers "B.Cu" "B.Mask" "B.Paste")
			(net "P3E_PCH_M2_TX_DN<1>")
		)
		(zone
			(layer "B.Cu")
			(hatch none 0.5)
			(connect_pads
				(clearance 0)
			)
			(min_thickness 0.25)
			(keepout
				(tracks allowed)
				(vias not_allowed)
				(pads allowed)
				(copperpour not_allowed)
				(footprints allowed)
			)
			(placement
				(enabled no)
				(sheetname "")
			)
			(fill
				(thermal_gap 0.5)
				(thermal_bridge_width 0.5)
				(island_removal_mode 0)
			)
			(polygon
				(pts
					(xy 385.59994 -29.809694) (xy 385.59994 -29.301694) (xy 385.98094 -29.301694) (xy 385.98094 -29.809694)
				)
			)
		)
		(zone
			(layer "B.Cu")
			(hatch none 0.5)
			(connect_pads
				(clearance 0)
			)
			(min_thickness 0.25)
			(keepout
				(tracks not_allowed)
				(vias allowed)
				(pads allowed)
				(copperpour not_allowed)
				(footprints allowed)
			)
			(placement
				(enabled no)
				(sheetname "")
			)
			(fill
				(thermal_gap 0.5)
				(thermal_bridge_width 0.5)
				(island_removal_mode 0)
			)
			(polygon
				(pts
					(xy 385.98094 -29.809694) (xy 385.98094 -29.301694) (xy 385.59994 -29.301694) (xy 385.59994 -29.809694)
				)
			)
		)
	)
	(footprint ""
		(layer "B.Cu")
		(at 414.528 -20.3962 -90)
		(property "Reference" "R1U7"
			(at 0 0 90)
			(layer "B.SilkS")
			(hide yes)
			(effects
				(font
					(size 1.27 1.27)
				)
				(justify mirror)
			)
		)
		(property "Value" ""
			(at 0 0 90)
			(layer "B.Fab")
			(effects
				(font
					(size 1.27 1.27)
				)
				(justify mirror)
			)
		)
		(duplicate_pad_numbers_are_jumpers no)
		(fp_poly
			(pts
				(xy 0.2794 -0.1016) (xy -0.2794 -0.1016) (xy -0.2794 0.9906) (xy 0.2794 0.9906)
			)
			(stroke
				(width 0)
				(type default)
			)
			(fill no)
			(layer "B.CrtYd")
		)
		(fp_line
			(start -0.2794 0.9906)
			(end -0.2794 -0.1016)
			(stroke
				(width 0.1)
				(type default)
			)
			(layer "B.Fab")
		)
		(fp_line
			(start 0.2794 0.9906)
			(end -0.2794 0.9906)
			(stroke
				(width 0.1)
				(type default)
			)
			(layer "B.Fab")
		)
		(fp_line
			(start -0.2794 -0.1016)
			(end 0.2794 -0.1016)
			(stroke
				(width 0.1)
				(type default)
			)
			(layer "B.Fab")
		)
		(fp_line
			(start 0.2794 -0.1016)
			(end 0.2794 0.9906)
			(stroke
				(width 0.1)
				(type default)
			)
			(layer "B.Fab")
		)
		(pad "1" smd rect
			(at 0 0 90)
			(size 0.508 0.508)
			(layers "B.Cu" "B.Mask" "B.Paste")
			(net "GND")
		)
		(pad "2" smd rect
			(at 0 0.889 90)
			(size 0.508 0.508)
			(layers "B.Cu" "B.Mask" "B.Paste")
			(net "PD_SP_ENTEST")
		)
		(zone
			(layer "B.Cu")
			(hatch none 0.5)
			(connect_pads
				(clearance 0)
			)
			(min_thickness 0.25)
			(keepout
				(tracks not_allowed)
				(vias allowed)
				(pads allowed)
				(copperpour not_allowed)
				(footprints allowed)
			)
			(placement
				(enabled no)
				(sheetname "")
			)
			(fill
				(thermal_gap 0.5)
				(thermal_bridge_width 0.5)
				(island_removal_mode 0)
			)
			(polygon
				(pts
					(xy 413.893 -20.1422) (xy 413.893 -20.6502) (xy 414.274 -20.6502) (xy 414.274 -20.1422)
				)
			)
		)
		(zone
			(layer "B.Cu")
			(hatch none 0.5)
			(connect_pads
				(clearance 0)
			)
			(min_thickness 0.25)
			(keepout
				(tracks allowed)
				(vias not_allowed)
				(pads allowed)
				(copperpour not_allowed)
				(footprints allowed)
			)
			(placement
				(enabled no)
				(sheetname "")
			)
			(fill
				(thermal_gap 0.5)
				(thermal_bridge_width 0.5)
				(island_removal_mode 0)
			)
			(polygon
				(pts
					(xy 414.274 -20.1422) (xy 414.274 -20.6502) (xy 413.893 -20.6502) (xy 413.893 -20.1422)
				)
			)
		)
	)
	(footprint ""
		(layer "B.Cu")
		(at 379.476 -19.304 90)
		(property "Reference" "CN8F2"
			(at 0.8382 -0.67818 90)
			(unlocked yes)
			(layer "B.SilkS")
			(effects
				(font
					(size 0.4064 0.254)
					(thickness 0.1524)
				)
				(justify left mirror)
			)
		)
		(property "Value" ""
			(at 0 0 90)
			(layer "B.Fab")
			(effects
				(font
					(size 1.27 1.27)
				)
				(justify mirror)
			)
		)
		(duplicate_pad_numbers_are_jumpers no)
		(fp_poly
			(pts
				(xy -0.3048 -0.1016) (xy -0.3048 0.9906) (xy 0.3048 0.9906) (xy 0.3048 -0.1016)
			)
			(stroke
				(width 0)
				(type default)
			)
			(fill no)
			(layer "B.CrtYd")
		)
		(fp_line
			(start 0.3048 -0.1016)
			(end 0.3048 0.9906)
			(stroke
				(width 0.1)
				(type default)
			)
			(layer "B.Fab")
		)
		(fp_line
			(start -0.3048 -0.1016)
			(end 0.3048 -0.1016)
			(stroke
				(width 0.1)
				(type default)
			)
			(layer "B.Fab")
		)
		(fp_line
			(start 0.3048 0.9906)
			(end -0.3048 0.9906)
			(stroke
				(width 0.1)
				(type default)
			)
			(layer "B.Fab")
		)
		(fp_line
			(start -0.3048 0.9906)
			(end -0.3048 -0.1016)
			(stroke
				(width 0.1)
				(type default)
			)
			(layer "B.Fab")
		)
		(pad "1" smd rect
			(at 0 0 270)
			(size 0.508 0.508)
			(layers "B.Cu" "B.Mask" "B.Paste")
			(net "P3V3_STBY")
		)
		(pad "2" smd rect
			(at 0 0.889 270)
			(size 0.508 0.508)
			(layers "B.Cu" "B.Mask" "B.Paste")
			(net "GND")
		)
		(zone
			(layer "B.Cu")
			(hatch none 0.5)
			(connect_pads
				(clearance 0)
			)
			(min_thickness 0.25)
			(keepout
				(tracks allowed)
				(vias not_allowed)
				(pads allowed)
				(copperpour not_allowed)
				(footprints allowed)
			)
			(placement
				(enabled no)
				(sheetname "")
			)
			(fill
				(thermal_gap 0.5)
				(thermal_bridge_width 0.5)
				(island_removal_mode 0)
			)
			(polygon
				(pts
					(xy 379.73 -19.558) (xy 379.73 -19.05) (xy 380.111 -19.05) (xy 380.111 -19.558)
				)
			)
		)
		(zone
			(layer "B.Cu")
			(hatch none 0.5)
			(connect_pads
				(clearance 0)
			)
			(min_thickness 0.25)
			(keepout
				(tracks not_allowed)
				(vias allowed)
				(pads allowed)
				(copperpour not_allowed)
				(footprints allowed)
			)
			(placement
				(enabled no)
				(sheetname "")
			)
			(fill
				(thermal_gap 0.5)
				(thermal_bridge_width 0.5)
				(island_removal_mode 0)
			)
			(polygon
				(pts
					(xy 380.111 -19.558) (xy 380.111 -19.05) (xy 379.73 -19.05) (xy 379.73 -19.558)
				)
			)
		)
	)
	(footprint ""
		(layer "B.Cu")
		(at 493.5474 -124.05868 180)
		(property "Reference" "R1M13"
			(at 0 0 0)
			(layer "B.SilkS")
			(hide yes)
			(effects
				(font
					(size 1.27 1.27)
				)
				(justify mirror)
			)
		)
		(property "Value" ""
			(at 0 0 0)
			(layer "B.Fab")
			(effects
				(font
					(size 1.27 1.27)
				)
				(justify mirror)
			)
		)
		(duplicate_pad_numbers_are_jumpers no)
		(fp_poly
			(pts
				(xy 0.2794 -0.1016) (xy -0.2794 -0.1016) (xy -0.2794 0.9906) (xy 0.2794 0.9906)
			)
			(stroke
				(width 0)
				(type default)
			)
			(fill no)
			(layer "B.CrtYd")
		)
		(fp_line
			(start 0.2794 0.9906)
			(end -0.2794 0.9906)
			(stroke
				(width 0.1)
				(type default)
			)
			(layer "B.Fab")
		)
		(fp_line
			(start 0.2794 -0.1016)
			(end 0.2794 0.9906)
			(stroke
				(width 0.1)
				(type default)
			)
			(layer "B.Fab")
		)
		(fp_line
			(start -0.2794 0.9906)
			(end -0.2794 -0.1016)
			(stroke
				(width 0.1)
				(type default)
			)
			(layer "B.Fab")
		)
		(fp_line
			(start -0.2794 -0.1016)
			(end 0.2794 -0.1016)
			(stroke
				(width 0.1)
				(type default)
			)
			(layer "B.Fab")
		)
		(pad "1" smd rect
			(at 0 0)
			(size 0.508 0.508)
			(layers "B.Cu" "B.Mask" "B.Paste")
			(net "LED_PCH_SSATA_HDD_N")
		)
		(pad "2" smd rect
			(at 0 0.889)
			(size 0.508 0.508)
			(layers "B.Cu" "B.Mask" "B.Paste")
			(net "LED_SAS_ACT_R_N")
		)
		(zone
			(layer "B.Cu")
			(hatch none 0.5)
			(connect_pads
				(clearance 0)
			)
			(min_thickness 0.25)
			(keepout
				(tracks not_allowed)
				(vias allowed)
				(pads allowed)
				(copperpour not_allowed)
				(footprints allowed)
			)
			(placement
				(enabled no)
				(sheetname "")
			)
			(fill
				(thermal_gap 0.5)
				(thermal_bridge_width 0.5)
				(island_removal_mode 0)
			)
			(polygon
				(pts
					(xy 493.2934 -124.69368) (xy 493.8014 -124.69368) (xy 493.8014 -124.31268) (xy 493.2934 -124.31268)
				)
			)
		)
		(zone
			(layer "B.Cu")
			(hatch none 0.5)
			(connect_pads
				(clearance 0)
			)
			(min_thickness 0.25)
			(keepout
				(tracks allowed)
				(vias not_allowed)
				(pads allowed)
				(copperpour not_allowed)
				(footprints allowed)
			)
			(placement
				(enabled no)
				(sheetname "")
			)
			(fill
				(thermal_gap 0.5)
				(thermal_bridge_width 0.5)
				(island_removal_mode 0)
			)
			(polygon
				(pts
					(xy 493.2934 -124.31268) (xy 493.8014 -124.31268) (xy 493.8014 -124.69368) (xy 493.2934 -124.69368)
				)
			)
		)
	)
)
